(kicad_pcb
	(version 20260206)
	(generator "pcbnew")
	(generator_version "10.0")
	(general
		(thickness 1.6)
		(legacy_teardrops no)
	)
	(paper "A4")
	(title_block
		(title "03242023_DA0F0TMBIJ0_F0T_Motherboard_J_brd_V01_OCP.brd")
		(comment 1 "Grand Teton / footprints 1119-1124 of 6105")
	)
	(layers
		(0 "F.Cu" signal "TOP")
		(4 "In1.Cu" signal "GND")
		(6 "In2.Cu" signal "IN1")
		(8 "In3.Cu" signal "GND1")
		(10 "In4.Cu" signal "IN2")
		(12 "In5.Cu" signal "GND2")
		(14 "In6.Cu" signal "IN3")
		(16 "In7.Cu" signal "GND3")
		(18 "In8.Cu" signal "VCC")
		(20 "In9.Cu" signal "VCC1")
		(22 "In10.Cu" signal "GND4")
		(24 "In11.Cu" signal "IN4")
		(26 "In12.Cu" signal "GND5")
		(28 "In13.Cu" signal "IN5")
		(30 "In14.Cu" signal "GND6")
		(32 "In15.Cu" signal "IN6")
		(34 "In16.Cu" signal "GND7")
		(2 "B.Cu" signal "BOTTOM")
		(9 "F.Adhes" user "F.Adhesive")
		(11 "B.Adhes" user "B.Adhesive")
		(13 "F.Paste" user "Package Geometry/Pastemask Top")
		(15 "B.Paste" user "Package Geometry/Pastemask Bottom")
		(5 "F.SilkS" user "Ref Des/Silkscreen Top")
		(7 "B.SilkS" user "Ref Des/Silkscreen Bottom")
		(1 "F.Mask" user "Board Geometry/Soldermask Top")
		(3 "B.Mask" user "Board Geometry/Soldermask Bottom")
		(17 "Dwgs.User" user "User.Drawings")
		(19 "Cmts.User" user "User.Comments")
		(21 "Eco1.User" user "User.Eco1")
		(23 "Eco2.User" user "User.Eco2")
		(25 "Edge.Cuts" user "Board Geometry/Outline")
		(27 "Margin" user)
		(31 "F.CrtYd" user "Package Geometry/Place Bound Top")
		(29 "B.CrtYd" user "Package Geometry/Place Bound Bottom")
		(35 "F.Fab" user "Ref Des/Assembly Top")
		(33 "B.Fab" user "Ref Des/Assembly Bottom")
	)
	(footprint ""
		(layer "F.Cu")
		(at 205.968092 -104.715056)
		(property "Reference" "Q35"
			(at -1.651 -2.25933 0)
			(unlocked yes)
			(layer "F.SilkS")
			(effects
				(font
					(size 0.7874 0.5842)
					(thickness 0.1524)
				)
				(justify left)
			)
		)
		(property "Value" ""
			(at 0 0 0)
			(layer "F.Fab")
			(effects
				(font
					(size 1.27 1.27)
				)
			)
		)
		(duplicate_pad_numbers_are_jumpers no)
		(fp_line
			(start -1.603248 -1.500124)
			(end 1.603248 -1.500124)
			(stroke
				(width 0.1524)
				(type default)
			)
			(layer "F.SilkS")
		)
		(fp_line
			(start -1.603248 1.500124)
			(end -1.603248 -1.500124)
			(stroke
				(width 0.1524)
				(type default)
			)
			(layer "F.SilkS")
		)
		(fp_line
			(start 1.603248 -1.500124)
			(end 1.603248 1.500124)
			(stroke
				(width 0.1524)
				(type default)
			)
			(layer "F.SilkS")
		)
		(fp_line
			(start 1.603248 1.500124)
			(end -1.603248 1.500124)
			(stroke
				(width 0.1524)
				(type default)
			)
			(layer "F.SilkS")
		)
		(fp_line
			(start -1.249934 -1.169924)
			(end -1.249934 -0.729996)
			(stroke
				(width 0.1)
				(type default)
			)
			(layer "F.Fab")
		)
		(fp_line
			(start -1.249934 -0.729996)
			(end -0.6985 -0.729996)
			(stroke
				(width 0.1)
				(type default)
			)
			(layer "F.Fab")
		)
		(fp_line
			(start -1.249934 0.729996)
			(end -1.249934 1.169924)
			(stroke
				(width 0.1)
				(type default)
			)
			(layer "F.Fab")
		)
		(fp_line
			(start -1.249934 1.169924)
			(end -0.700024 1.169924)
			(stroke
				(width 0.1)
				(type default)
			)
			(layer "F.Fab")
		)
		(fp_line
			(start -0.700024 -1.500124)
			(end -0.700024 -1.169924)
			(stroke
				(width 0.1)
				(type default)
			)
			(layer "F.Fab")
		)
		(fp_line
			(start -0.700024 -1.169924)
			(end -1.249934 -1.169924)
			(stroke
				(width 0.1)
				(type default)
			)
			(layer "F.Fab")
		)
		(fp_line
			(start -0.700024 1.169924)
			(end -0.700024 1.500124)
			(stroke
				(width 0.1)
				(type default)
			)
			(layer "F.Fab")
		)
		(fp_line
			(start -0.700024 1.500124)
			(end 0.700024 1.500124)
			(stroke
				(width 0.1)
				(type default)
			)
			(layer "F.Fab")
		)
		(fp_line
			(start -0.6985 -0.729996)
			(end -0.6985 0.729996)
			(stroke
				(width 0.1)
				(type default)
			)
			(layer "F.Fab")
		)
		(fp_line
			(start -0.6985 0.729996)
			(end -1.249934 0.729996)
			(stroke
				(width 0.1)
				(type default)
			)
			(layer "F.Fab")
		)
		(fp_line
			(start 0.700024 -1.500124)
			(end -0.700024 -1.500124)
			(stroke
				(width 0.1)
				(type default)
			)
			(layer "F.Fab")
		)
		(fp_line
			(start 0.700024 -0.219964)
			(end 0.700024 -1.500124)
			(stroke
				(width 0.1)
				(type default)
			)
			(layer "F.Fab")
		)
		(fp_line
			(start 0.700024 0.219964)
			(end 1.249934 0.219964)
			(stroke
				(width 0.1)
				(type default)
			)
			(layer "F.Fab")
		)
		(fp_line
			(start 0.700024 1.500124)
			(end 0.700024 0.219964)
			(stroke
				(width 0.1)
				(type default)
			)
			(layer "F.Fab")
		)
		(fp_line
			(start 1.249934 -0.219964)
			(end 0.700024 -0.219964)
			(stroke
				(width 0.1)
				(type default)
			)
			(layer "F.Fab")
		)
		(fp_line
			(start 1.249934 0.219964)
			(end 1.249934 -0.219964)
			(stroke
				(width 0.1)
				(type default)
			)
			(layer "F.Fab")
		)
		(fp_rect
			(start -0.700024 1.500124)
			(end 0.700024 -1.500124)
			(stroke
				(width 0)
				(type default)
			)
			(fill no)
			(layer "F.Fab")
		)
		(pad "D" smd rect
			(at 0.999998 0 270)
			(size 0.8128 0.9144)
			(layers "F.Cu" "F.Mask" "F.Paste")
			(net "RST_SRTCRST_N")
		)
		(pad "G" smd rect
			(at -0.999998 -0.94996 270)
			(size 0.8128 0.9144)
			(layers "F.Cu" "F.Mask" "F.Paste")
			(net "RST_PFR_OVR_SRTC")
		)
		(pad "S" smd rect
			(at -0.999998 0.94996 270)
			(size 0.8128 0.9144)
			(layers "F.Cu" "F.Mask" "F.Paste")
			(net "GND")
		)
	)
	(footprint ""
		(layer "F.Cu")
		(at 120.0912 -415.276538 180)
		(property "Reference" "R4481"
			(at 0 0 180)
			(layer "F.SilkS")
			(hide yes)
			(effects
				(font
					(size 1.27 1.27)
				)
			)
		)
		(property "Value" ""
			(at 0 0 180)
			(layer "F.Fab")
			(effects
				(font
					(size 1.27 1.27)
				)
			)
		)
		(duplicate_pad_numbers_are_jumpers no)
		(fp_line
			(start 0.7874 0.4064)
			(end -0.7874 0.4064)
			(stroke
				(width 0.1524)
				(type default)
			)
			(layer "F.SilkS")
		)
		(fp_line
			(start 0.7874 -0.4064)
			(end 0.7874 0.4064)
			(stroke
				(width 0.1524)
				(type default)
			)
			(layer "F.SilkS")
		)
		(fp_line
			(start -0.7874 0.4064)
			(end -0.7874 -0.4064)
			(stroke
				(width 0.1524)
				(type default)
			)
			(layer "F.SilkS")
		)
		(fp_line
			(start -0.7874 -0.4064)
			(end 0.7874 -0.4064)
			(stroke
				(width 0.1524)
				(type default)
			)
			(layer "F.SilkS")
		)
		(fp_line
			(start 0.67945 0.3048)
			(end 0.120396 0.3048)
			(stroke
				(width 0.1)
				(type default)
			)
			(layer "F.Fab")
		)
		(fp_line
			(start 0.67945 -0.3048)
			(end 0.67945 0.3048)
			(stroke
				(width 0.1)
				(type default)
			)
			(layer "F.Fab")
		)
		(fp_line
			(start 0.12065 -0.2794)
			(end 0.12065 -0.3048)
			(stroke
				(width 0.1)
				(type default)
			)
			(layer "F.Fab")
		)
		(fp_line
			(start 0.12065 -0.3048)
			(end 0.67945 -0.3048)
			(stroke
				(width 0.1)
				(type default)
			)
			(layer "F.Fab")
		)
		(fp_line
			(start 0.120396 0.3048)
			(end 0.120396 0.2794)
			(stroke
				(width 0.1)
				(type default)
			)
			(layer "F.Fab")
		)
		(fp_line
			(start 0.120396 0.2794)
			(end -0.12065 0.2794)
			(stroke
				(width 0.1)
				(type default)
			)
			(layer "F.Fab")
		)
		(fp_line
			(start -0.12065 0.3048)
			(end -0.67945 0.3048)
			(stroke
				(width 0.1)
				(type default)
			)
			(layer "F.Fab")
		)
		(fp_line
			(start -0.12065 0.2794)
			(end -0.12065 0.3048)
			(stroke
				(width 0.1)
				(type default)
			)
			(layer "F.Fab")
		)
		(fp_line
			(start -0.12065 -0.2794)
			(end 0.12065 -0.2794)
			(stroke
				(width 0.1)
				(type default)
			)
			(layer "F.Fab")
		)
		(fp_line
			(start -0.12065 -0.305054)
			(end -0.12065 -0.2794)
			(stroke
				(width 0.1)
				(type default)
			)
			(layer "F.Fab")
		)
		(fp_line
			(start -0.67945 0.3048)
			(end -0.67945 -0.305054)
			(stroke
				(width 0.1)
				(type default)
			)
			(layer "F.Fab")
		)
		(fp_line
			(start -0.67945 -0.305054)
			(end -0.12065 -0.305054)
			(stroke
				(width 0.1)
				(type default)
			)
			(layer "F.Fab")
		)
		(pad "1" smd circle
			(at -0.40005 0 180)
			(size 0 0)
			(layers "F.Cu" "F.Mask" "F.Paste")
			(net "SMB_HOST_CLK_BUF_ISO_3V3AUX_SDA")
		)
		(pad "2" smd circle
			(at 0.40005 0 180)
			(size 0 0)
			(layers "F.Cu" "F.Mask" "F.Paste")
			(net "SMB_HOST_9ZXL045_3V3AUX_SDA")
		)
	)
	(footprint ""
		(layer "F.Cu")
		(at 447.589402 -77.829918 90)
		(property "Reference" "PR830"
			(at 0 0 90)
			(layer "F.SilkS")
			(hide yes)
			(effects
				(font
					(size 1.27 1.27)
				)
			)
		)
		(property "Value" ""
			(at 0 0 90)
			(layer "F.Fab")
			(effects
				(font
					(size 1.27 1.27)
				)
			)
		)
		(duplicate_pad_numbers_are_jumpers no)
		(fp_line
			(start 0.7874 -0.4064)
			(end 0.7874 0.4064)
			(stroke
				(width 0.1524)
				(type default)
			)
			(layer "F.SilkS")
		)
		(fp_line
			(start -0.7874 -0.4064)
			(end 0.7874 -0.4064)
			(stroke
				(width 0.1524)
				(type default)
			)
			(layer "F.SilkS")
		)
		(fp_line
			(start 0.7874 0.4064)
			(end -0.7874 0.4064)
			(stroke
				(width 0.1524)
				(type default)
			)
			(layer "F.SilkS")
		)
		(fp_line
			(start -0.7874 0.4064)
			(end -0.7874 -0.4064)
			(stroke
				(width 0.1524)
				(type default)
			)
			(layer "F.SilkS")
		)
		(fp_line
			(start -0.12065 -0.305054)
			(end -0.12065 -0.2794)
			(stroke
				(width 0.1)
				(type default)
			)
			(layer "F.Fab")
		)
		(fp_line
			(start -0.67945 -0.305054)
			(end -0.12065 -0.305054)
			(stroke
				(width 0.1)
				(type default)
			)
			(layer "F.Fab")
		)
		(fp_line
			(start 0.67945 -0.3048)
			(end 0.67945 0.3048)
			(stroke
				(width 0.1)
				(type default)
			)
			(layer "F.Fab")
		)
		(fp_line
			(start 0.12065 -0.3048)
			(end 0.67945 -0.3048)
			(stroke
				(width 0.1)
				(type default)
			)
			(layer "F.Fab")
		)
		(fp_line
			(start 0.12065 -0.2794)
			(end 0.12065 -0.3048)
			(stroke
				(width 0.1)
				(type default)
			)
			(layer "F.Fab")
		)
		(fp_line
			(start -0.12065 -0.2794)
			(end 0.12065 -0.2794)
			(stroke
				(width 0.1)
				(type default)
			)
			(layer "F.Fab")
		)
		(fp_line
			(start 0.120396 0.2794)
			(end -0.12065 0.2794)
			(stroke
				(width 0.1)
				(type default)
			)
			(layer "F.Fab")
		)
		(fp_line
			(start -0.12065 0.2794)
			(end -0.12065 0.3048)
			(stroke
				(width 0.1)
				(type default)
			)
			(layer "F.Fab")
		)
		(fp_line
			(start 0.67945 0.3048)
			(end 0.120396 0.3048)
			(stroke
				(width 0.1)
				(type default)
			)
			(layer "F.Fab")
		)
		(fp_line
			(start 0.120396 0.3048)
			(end 0.120396 0.2794)
			(stroke
				(width 0.1)
				(type default)
			)
			(layer "F.Fab")
		)
		(fp_line
			(start -0.12065 0.3048)
			(end -0.67945 0.3048)
			(stroke
				(width 0.1)
				(type default)
			)
			(layer "F.Fab")
		)
		(fp_line
			(start -0.67945 0.3048)
			(end -0.67945 -0.305054)
			(stroke
				(width 0.1)
				(type default)
			)
			(layer "F.Fab")
		)
		(pad "1" smd circle
			(at -0.40005 0 90)
			(size 0 0)
			(layers "F.Cu" "F.Mask" "F.Paste")
			(net "P3V3_AUX_FB")
		)
		(pad "2" smd circle
			(at 0.40005 0 90)
			(size 0 0)
			(layers "F.Cu" "F.Mask" "F.Paste")
			(net "GND")
		)
	)
	(footprint ""
		(layer "F.Cu")
		(at 430.600104 -133.478778)
		(property "Reference" "C3273"
			(at 0 0 0)
			(layer "F.SilkS")
			(hide yes)
			(effects
				(font
					(size 1.27 1.27)
				)
			)
		)
		(property "Value" ""
			(at 0 0 0)
			(layer "F.Fab")
			(effects
				(font
					(size 1.27 1.27)
				)
			)
		)
		(duplicate_pad_numbers_are_jumpers no)
		(fp_line
			(start -0.7874 -0.4064)
			(end 0.7874 -0.4064)
			(stroke
				(width 0.1524)
				(type default)
			)
			(layer "F.SilkS")
		)
		(fp_line
			(start -0.7874 0.4064)
			(end -0.7874 -0.4064)
			(stroke
				(width 0.1524)
				(type default)
			)
			(layer "F.SilkS")
		)
		(fp_line
			(start 0.7874 -0.4064)
			(end 0.7874 0.4064)
			(stroke
				(width 0.1524)
				(type default)
			)
			(layer "F.SilkS")
		)
		(fp_line
			(start 0.7874 0.4064)
			(end -0.7874 0.4064)
			(stroke
				(width 0.1524)
				(type default)
			)
			(layer "F.SilkS")
		)
		(fp_line
			(start -0.67945 -0.305054)
			(end -0.12065 -0.305054)
			(stroke
				(width 0.1)
				(type default)
			)
			(layer "F.Fab")
		)
		(fp_line
			(start -0.67945 0.3048)
			(end -0.67945 -0.305054)
			(stroke
				(width 0.1)
				(type default)
			)
			(layer "F.Fab")
		)
		(fp_line
			(start -0.12065 -0.305054)
			(end -0.12065 -0.2794)
			(stroke
				(width 0.1)
				(type default)
			)
			(layer "F.Fab")
		)
		(fp_line
			(start -0.12065 -0.2794)
			(end 0.12065 -0.2794)
			(stroke
				(width 0.1)
				(type default)
			)
			(layer "F.Fab")
		)
		(fp_line
			(start -0.12065 0.2794)
			(end -0.12065 0.3048)
			(stroke
				(width 0.1)
				(type default)
			)
			(layer "F.Fab")
		)
		(fp_line
			(start -0.12065 0.3048)
			(end -0.67945 0.3048)
			(stroke
				(width 0.1)
				(type default)
			)
			(layer "F.Fab")
		)
		(fp_line
			(start 0.120396 0.2794)
			(end -0.12065 0.2794)
			(stroke
				(width 0.1)
				(type default)
			)
			(layer "F.Fab")
		)
		(fp_line
			(start 0.120396 0.3048)
			(end 0.120396 0.2794)
			(stroke
				(width 0.1)
				(type default)
			)
			(layer "F.Fab")
		)
		(fp_line
			(start 0.12065 -0.3048)
			(end 0.67945 -0.3048)
			(stroke
				(width 0.1)
				(type default)
			)
			(layer "F.Fab")
		)
		(fp_line
			(start 0.12065 -0.2794)
			(end 0.12065 -0.3048)
			(stroke
				(width 0.1)
				(type default)
			)
			(layer "F.Fab")
		)
		(fp_line
			(start 0.67945 -0.3048)
			(end 0.67945 0.3048)
			(stroke
				(width 0.1)
				(type default)
			)
			(layer "F.Fab")
		)
		(fp_line
			(start 0.67945 0.3048)
			(end 0.120396 0.3048)
			(stroke
				(width 0.1)
				(type default)
			)
			(layer "F.Fab")
		)
		(pad "1" smd circle
			(at -0.40005 0)
			(size 0 0)
			(layers "F.Cu" "F.Mask" "F.Paste")
			(net "PWRGD_PVCCINFAON_CPU0_R")
		)
		(pad "2" smd circle
			(at 0.40005 0)
			(size 0 0)
			(layers "F.Cu" "F.Mask" "F.Paste")
			(net "GND")
		)
	)
	(footprint ""
		(layer "F.Cu")
		(at 123.265184 -338.17814 -90)
		(property "Reference" "PC531"
			(at 0 0 270)
			(layer "F.SilkS")
			(hide yes)
			(effects
				(font
					(size 1.27 1.27)
				)
			)
		)
		(property "Value" ""
			(at 0 0 270)
			(layer "F.Fab")
			(effects
				(font
					(size 1.27 1.27)
				)
			)
		)
		(duplicate_pad_numbers_are_jumpers no)
		(fp_line
			(start -0.7874 0.4064)
			(end -0.7874 -0.4064)
			(stroke
				(width 0.1524)
				(type default)
			)
			(layer "F.SilkS")
		)
		(fp_line
			(start 0.7874 0.4064)
			(end -0.7874 0.4064)
			(stroke
				(width 0.1524)
				(type default)
			)
			(layer "F.SilkS")
		)
		(fp_line
			(start -0.7874 -0.4064)
			(end 0.7874 -0.4064)
			(stroke
				(width 0.1524)
				(type default)
			)
			(layer "F.SilkS")
		)
		(fp_line
			(start 0.7874 -0.4064)
			(end 0.7874 0.4064)
			(stroke
				(width 0.1524)
				(type default)
			)
			(layer "F.SilkS")
		)
		(fp_line
			(start -0.67945 0.3048)
			(end -0.67945 -0.305054)
			(stroke
				(width 0.1)
				(type default)
			)
			(layer "F.Fab")
		)
		(fp_line
			(start -0.12065 0.3048)
			(end -0.67945 0.3048)
			(stroke
				(width 0.1)
				(type default)
			)
			(layer "F.Fab")
		)
		(fp_line
			(start 0.120396 0.3048)
			(end 0.120396 0.2794)
			(stroke
				(width 0.1)
				(type default)
			)
			(layer "F.Fab")
		)
		(fp_line
			(start 0.67945 0.3048)
			(end 0.120396 0.3048)
			(stroke
				(width 0.1)
				(type default)
			)
			(layer "F.Fab")
		)
		(fp_line
			(start -0.12065 0.2794)
			(end -0.12065 0.3048)
			(stroke
				(width 0.1)
				(type default)
			)
			(layer "F.Fab")
		)
		(fp_line
			(start 0.120396 0.2794)
			(end -0.12065 0.2794)
			(stroke
				(width 0.1)
				(type default)
			)
			(layer "F.Fab")
		)
		(fp_line
			(start -0.12065 -0.2794)
			(end 0.12065 -0.2794)
			(stroke
				(width 0.1)
				(type default)
			)
			(layer "F.Fab")
		)
		(fp_line
			(start 0.12065 -0.2794)
			(end 0.12065 -0.3048)
			(stroke
				(width 0.1)
				(type default)
			)
			(layer "F.Fab")
		)
		(fp_line
			(start 0.12065 -0.3048)
			(end 0.67945 -0.3048)
			(stroke
				(width 0.1)
				(type default)
			)
			(layer "F.Fab")
		)
		(fp_line
			(start 0.67945 -0.3048)
			(end 0.67945 0.3048)
			(stroke
				(width 0.1)
				(type default)
			)
			(layer "F.Fab")
		)
		(fp_line
			(start -0.67945 -0.305054)
			(end -0.12065 -0.305054)
			(stroke
				(width 0.1)
				(type default)
			)
			(layer "F.Fab")
		)
		(fp_line
			(start -0.12065 -0.305054)
			(end -0.12065 -0.2794)
			(stroke
				(width 0.1)
				(type default)
			)
			(layer "F.Fab")
		)
		(pad "1" smd circle
			(at -0.40005 0 270)
			(size 0 0)
			(layers "F.Cu" "F.Mask" "F.Paste")
			(net "SW_PVCCIN_CPU1_BOOT4_R")
		)
		(pad "2" smd circle
			(at 0.40005 0 270)
			(size 0 0)
			(layers "F.Cu" "F.Mask" "F.Paste")
			(net "SW_PVCCIN_CPU1_BOOTR4")
		)
	)
	(footprint ""
		(layer "F.Cu")
		(at 183.49849 -358.15778 -90)
		(property "Reference" "PC1197"
			(at 0 0 270)
			(layer "F.SilkS")
			(hide yes)
			(effects
				(font
					(size 1.27 1.27)
				)
			)
		)
		(property "Value" ""
			(at 0 0 270)
			(layer "F.Fab")
			(effects
				(font
					(size 1.27 1.27)
				)
			)
		)
		(duplicate_pad_numbers_are_jumpers no)
		(fp_line
			(start -0.7874 0.4064)
			(end -0.7874 -0.4064)
			(stroke
				(width 0.1524)
				(type default)
			)
			(layer "F.SilkS")
		)
		(fp_line
			(start 0.7874 0.4064)
			(end -0.7874 0.4064)
			(stroke
				(width 0.1524)
				(type default)
			)
			(layer "F.SilkS")
		)
		(fp_line
			(start -0.7874 -0.4064)
			(end 0.7874 -0.4064)
			(stroke
				(width 0.1524)
				(type default)
			)
			(layer "F.SilkS")
		)
		(fp_line
			(start 0.7874 -0.4064)
			(end 0.7874 0.4064)
			(stroke
				(width 0.1524)
				(type default)
			)
			(layer "F.SilkS")
		)
		(fp_line
			(start -0.67945 0.3048)
			(end -0.67945 -0.305054)
			(stroke
				(width 0.1)
				(type default)
			)
			(layer "F.Fab")
		)
		(fp_line
			(start -0.12065 0.3048)
			(end -0.67945 0.3048)
			(stroke
				(width 0.1)
				(type default)
			)
			(layer "F.Fab")
		)
		(fp_line
			(start 0.120396 0.3048)
			(end 0.120396 0.2794)
			(stroke
				(width 0.1)
				(type default)
			)
			(layer "F.Fab")
		)
		(fp_line
			(start 0.67945 0.3048)
			(end 0.120396 0.3048)
			(stroke
				(width 0.1)
				(type default)
			)
			(layer "F.Fab")
		)
		(fp_line
			(start -0.12065 0.2794)
			(end -0.12065 0.3048)
			(stroke
				(width 0.1)
				(type default)
			)
			(layer "F.Fab")
		)
		(fp_line
			(start 0.120396 0.2794)
			(end -0.12065 0.2794)
			(stroke
				(width 0.1)
				(type default)
			)
			(layer "F.Fab")
		)
		(fp_line
			(start -0.12065 -0.2794)
			(end 0.12065 -0.2794)
			(stroke
				(width 0.1)
				(type default)
			)
			(layer "F.Fab")
		)
		(fp_line
			(start 0.12065 -0.2794)
			(end 0.12065 -0.3048)
			(stroke
				(width 0.1)
				(type default)
			)
			(layer "F.Fab")
		)
		(fp_line
			(start 0.12065 -0.3048)
			(end 0.67945 -0.3048)
			(stroke
				(width 0.1)
				(type default)
			)
			(layer "F.Fab")
		)
		(fp_line
			(start 0.67945 -0.3048)
			(end 0.67945 0.3048)
			(stroke
				(width 0.1)
				(type default)
			)
			(layer "F.Fab")
		)
		(fp_line
			(start -0.67945 -0.305054)
			(end -0.12065 -0.305054)
			(stroke
				(width 0.1)
				(type default)
			)
			(layer "F.Fab")
		)
		(fp_line
			(start -0.12065 -0.305054)
			(end -0.12065 -0.2794)
			(stroke
				(width 0.1)
				(type default)
			)
			(layer "F.Fab")
		)
		(pad "1" smd circle
			(at -0.40005 0 270)
			(size 0 0)
			(layers "F.Cu" "F.Mask" "F.Paste")
			(net "SW_PVCCFA_EHV_FIVRA_CPU1_BOOT3_")
		)
		(pad "2" smd circle
			(at 0.40005 0 270)
			(size 0 0)
			(layers "F.Cu" "F.Mask" "F.Paste")
			(net "SW_PVCCFA_EHV_FIVRA_CPU1_BOOTR3")
		)
	)
)
